FILE_TYPE = MACRO_DRAWING;
SET COLOR_WIRE YELLOW;
SET COLOR_PROP MONO;
SET COLOR_DOT WHITE;
SET COLOR_ARC YELLOW;
SET COLOR_BODY GREEN;
SET COLOR_NOTE MONO;
SET PROP_DISPLAY VALUE;
SET PAGE_NUMBER P20;
FORCEADD INTEL_CORP_BPAGE..1
(0 0);
FORCEPROP 1 LAST CDS_CON_LAST_MODIFIED Fri Jun 16 17:48:06 2017
J 0
(-1425 325);
PAINT ORANGE (-1425 325);
DISPLAY INVISIBLE (-1425 325);
FORCEPROP 1 LAST CUSTOM_TXT_CDS <CURRENT_DESIGN_SHEET> OF <TOTAL_DESIGN_SHEETS>
J 0
(-500 25);
PAINT ORANGE (-500 25);
FORCEPROP 1 LAST CUSTOM_TXT_CDS <CON_LAST_MODIFIED>
J 0
(-4000 100);
PAINT ORANGE (-4000 100);
FORCEPROP 2 LAST CUSTOM_TXT_CDS <XR_PAGE_TITLE>
J 0
(-7890 5250);
DISPLAY 0.638298 (-7890 5250);
PAINT PINK (-7890 5250);
DISPLAY INVISIBLE (-7890 5250);
FORCEPROP 1 LAST SCH_TITLE MISC. VOLTAGE INFO
J 0
(-7950 50);
DISPLAY 1.212766 (-7950 50);
PAINT ORANGE (-7950 50);
FORCEPROP 2 LAST PAGE_BORDER TRUE
J 0
(-7890 5250);
DISPLAY 0.638298 (-7890 5250);
PAINT PINK (-7890 5250);
DISPLAY INVISIBLE (-7890 5250);
FORCEPROP 2 LAST CDS_LIB mstr_symbols
J 0
(0 0);
PAINT MONO (0 0);
DISPLAY INVISIBLE (0 0);
FORCEPROP 1 LAST COMMENT_BODY TRUE
J 0
(12 12);
DISPLAY 0.468085 (12 12);
PAINT GREEN (12 12);
DISPLAY INVISIBLE (12 12);
FORCEPROP 2 LAST CDS_XR_PAGE_TITLE CR-20 : @BASEBOARD_FAB2_LIB.BASEBOARD_FAB2(SCH_1):PAGE20
J 0
(-7890 5250);
DISPLAY 0.638298 (-7890 5250);
PAINT PINK (-7890 5250);
DISPLAY INVISIBLE (-7890 5250);
FORCENOTE
$CDS_IMAGE|MISC. VOLTAGE INFO_20160505.jpg|6666|5000
(-4050 2525) 0;
DISPLAY LEFT (-4050 2525);
QUIT
